# S9S_MB_2U (Grand Teton) — schematic netlist excerpt (pin names and nets, part order shuffled) for the footprints in the layout excerpt that follows; sources: Cadence DE-HDL packaged netlist, KiCad conversion of 03242023_DA0F0TMBIJ0_F0T_Motherboard_J_brd_V01_OCP.brd

PC1185_P0_3  Q_CAP  22UF 4V 20% X6S  pkg C0805  page 272 : A = PVCCFA_EHV_FIVRA_CPU0 ; B = GND
C2022  Q_CAP  0.1UF 25V 10% X7R  pkg 0402  page 172 : A = VSENSE_P12V_INA230_5_INP ; B = VSENSE_P12V_INA230_5_INN
C2331  Q_CAP  10UF 6.3V 20% X6S  pkg C0603  page 211 : A = P3V3_9ZXL045_VDDA ; B = GND

(kicad_pcb
	(version 20260206)
	(generator "pcbnew")
	(generator_version "10.0")
	(general
		(thickness 1.6)
		(legacy_teardrops no)
	)
	(paper "A4")
	(title_block
		(title "03242023_DA0F0TMBIJ0_F0T_Motherboard_J_brd_V01_OCP.brd")
		(comment 1 "Grand Teton / footprints 5923-5925 of 6105")
	)
	(layers
		(0 "F.Cu" signal "TOP")
		(4 "In1.Cu" signal "GND")
		(6 "In2.Cu" signal "IN1")
		(8 "In3.Cu" signal "GND1")
		(10 "In4.Cu" signal "IN2")
		(12 "In5.Cu" signal "GND2")
		(14 "In6.Cu" signal "IN3")
		(16 "In7.Cu" signal "GND3")
		(18 "In8.Cu" signal "VCC")
		(20 "In9.Cu" signal "VCC1")
		(22 "In10.Cu" signal "GND4")
		(24 "In11.Cu" signal "IN4")
		(26 "In12.Cu" signal "GND5")
		(28 "In13.Cu" signal "IN5")
		(30 "In14.Cu" signal "GND6")
		(32 "In15.Cu" signal "IN6")
		(34 "In16.Cu" signal "GND7")
		(2 "B.Cu" signal "BOTTOM")
		(9 "F.Adhes" user "F.Adhesive")
		(11 "B.Adhes" user "B.Adhesive")
		(13 "F.Paste" user "Package Geometry/Pastemask Top")
		(15 "B.Paste" user "Package Geometry/Pastemask Bottom")
		(5 "F.SilkS" user "Ref Des/Silkscreen Top")
		(7 "B.SilkS" user "Ref Des/Silkscreen Bottom")
		(1 "F.Mask" user "Board Geometry/Soldermask Top")
		(3 "B.Mask" user "Board Geometry/Soldermask Bottom")
		(17 "Dwgs.User" user "User.Drawings")
		(19 "Cmts.User" user "User.Comments")
		(21 "Eco1.User" user "User.Eco1")
		(23 "Eco2.User" user "User.Eco2")
		(25 "Edge.Cuts" user "Board Geometry/Outline")
		(27 "Margin" user)
		(31 "F.CrtYd" user "Package Geometry/Place Bound Top")
		(29 "B.CrtYd" user "Package Geometry/Place Bound Bottom")
		(35 "F.Fab" user "Ref Des/Assembly Top")
		(33 "B.Fab" user "Ref Des/Assembly Bottom")
	)
	(footprint ""
		(layer "B.Cu")
		(at 430.518316 -352.974148 -90)
		(property "Reference" "PC1185_P0_3"
			(at 0 0 90)
			(layer "B.SilkS")
			(hide yes)
			(effects
				(font
					(size 1.27 1.27)
				)
				(justify mirror)
			)
		)
		(property "Value" ""
			(at 0 0 90)
			(layer "B.Fab")
			(effects
				(font
					(size 1.27 1.27)
				)
				(justify mirror)
			)
		)
		(duplicate_pad_numbers_are_jumpers no)
		(fp_line
			(start -1.524 0.762)
			(end 1.524 0.762)
			(stroke
				(width 0.1524)
				(type default)
			)
			(layer "B.SilkS")
		)
		(fp_line
			(start 1.524 0.762)
			(end 1.524 -0.762)
			(stroke
				(width 0.1524)
				(type default)
			)
			(layer "B.SilkS")
		)
		(fp_line
			(start -1.524 -0.762)
			(end -1.524 0.762)
			(stroke
				(width 0.1524)
				(type default)
			)
			(layer "B.SilkS")
		)
		(fp_line
			(start 1.524 -0.762)
			(end -1.524 -0.762)
			(stroke
				(width 0.1524)
				(type default)
			)
			(layer "B.SilkS")
		)
		(fp_line
			(start -1.1049 0.724916)
			(end -1.1049 -0.724916)
			(stroke
				(width 0.1)
				(type default)
			)
			(layer "B.Fab")
		)
		(fp_line
			(start 1.1049 0.724916)
			(end -1.1049 0.724916)
			(stroke
				(width 0.1)
				(type default)
			)
			(layer "B.Fab")
		)
		(fp_line
			(start -1.1049 -0.724916)
			(end 1.1049 -0.724916)
			(stroke
				(width 0.1)
				(type default)
			)
			(layer "B.Fab")
		)
		(fp_line
			(start 1.1049 -0.724916)
			(end 1.1049 0.724916)
			(stroke
				(width 0.1)
				(type default)
			)
			(layer "B.Fab")
		)
		(pad "1" smd rect
			(at 0.889 0 270)
			(size 1.016 1.27)
			(layers "B.Cu" "B.Mask" "B.Paste")
			(net "PVCCFA_EHV_FIVRA_CPU0")
		)
		(pad "2" smd rect
			(at -0.889 0 270)
			(size 1.016 1.27)
			(layers "B.Cu" "B.Mask" "B.Paste")
			(net "GND")
		)
	)
	(footprint ""
		(layer "B.Cu")
		(at 109.125512 -415.047938 90)
		(property "Reference" "C2331"
			(at 0 0 90)
			(layer "B.SilkS")
			(hide yes)
			(effects
				(font
					(size 1.27 1.27)
				)
				(justify mirror)
			)
		)
		(property "Value" ""
			(at 0 0 90)
			(layer "B.Fab")
			(effects
				(font
					(size 1.27 1.27)
				)
				(justify mirror)
			)
		)
		(duplicate_pad_numbers_are_jumpers no)
		(fp_line
			(start 1.2954 -0.5842)
			(end -1.2954 -0.5842)
			(stroke
				(width 0.1524)
				(type default)
			)
			(layer "B.SilkS")
		)
		(fp_line
			(start 0 -0.5842)
			(end 0 0.5842)
			(stroke
				(width 0.1524)
				(type default)
			)
			(layer "B.SilkS")
		)
		(fp_line
			(start -1.2954 -0.5842)
			(end -1.2954 0.5842)
			(stroke
				(width 0.1524)
				(type default)
			)
			(layer "B.SilkS")
		)
		(fp_line
			(start 1.2954 0.5842)
			(end 1.2954 -0.5842)
			(stroke
				(width 0.1524)
				(type default)
			)
			(layer "B.SilkS")
		)
		(fp_line
			(start -1.2954 0.5842)
			(end 1.2954 0.5842)
			(stroke
				(width 0.1524)
				(type default)
			)
			(layer "B.SilkS")
		)
		(fp_line
			(start 0.8636 -0.4572)
			(end -0.8636 -0.4572)
			(stroke
				(width 0.1)
				(type default)
			)
			(layer "B.Fab")
		)
		(fp_line
			(start -0.8636 -0.4572)
			(end -0.8636 -0.4064)
			(stroke
				(width 0.1)
				(type default)
			)
			(layer "B.Fab")
		)
		(fp_line
			(start 1.1938 -0.4064)
			(end 0.8636 -0.4064)
			(stroke
				(width 0.1)
				(type default)
			)
			(layer "B.Fab")
		)
		(fp_line
			(start 0.8636 -0.4064)
			(end 0.8636 -0.4572)
			(stroke
				(width 0.1)
				(type default)
			)
			(layer "B.Fab")
		)
		(fp_line
			(start -0.8636 -0.4064)
			(end -1.1938 -0.4064)
			(stroke
				(width 0.1)
				(type default)
			)
			(layer "B.Fab")
		)
		(fp_line
			(start -1.1938 -0.4064)
			(end -1.1938 0.4064)
			(stroke
				(width 0.1)
				(type default)
			)
			(layer "B.Fab")
		)
		(fp_line
			(start 1.1938 0.4064)
			(end 1.1938 -0.4064)
			(stroke
				(width 0.1)
				(type default)
			)
			(layer "B.Fab")
		)
		(fp_line
			(start 0.8636 0.4064)
			(end 1.1938 0.4064)
			(stroke
				(width 0.1)
				(type default)
			)
			(layer "B.Fab")
		)
		(fp_line
			(start -0.8636 0.4064)
			(end -0.8636 0.4572)
			(stroke
				(width 0.1)
				(type default)
			)
			(layer "B.Fab")
		)
		(fp_line
			(start -1.1938 0.4064)
			(end -0.8636 0.4064)
			(stroke
				(width 0.1)
				(type default)
			)
			(layer "B.Fab")
		)
		(fp_line
			(start 0.8636 0.4572)
			(end 0.8636 0.4064)
			(stroke
				(width 0.1)
				(type default)
			)
			(layer "B.Fab")
		)
		(fp_line
			(start -0.8636 0.4572)
			(end 0.8636 0.4572)
			(stroke
				(width 0.1)
				(type default)
			)
			(layer "B.Fab")
		)
		(pad "1" smd rect
			(at 0.7366 0)
			(size 0.7112 0.8128)
			(layers "B.Cu" "B.Mask" "B.Paste")
			(net "P3V3_9ZXL045_VDDA")
		)
		(pad "2" smd rect
			(at -0.7366 0)
			(size 0.7112 0.8128)
			(layers "B.Cu" "B.Mask" "B.Paste")
			(net "GND")
		)
	)
	(footprint ""
		(layer "B.Cu")
		(at 205.28788 -35.956748 90)
		(property "Reference" "C2022"
			(at 0 0 90)
			(layer "B.SilkS")
			(hide yes)
			(effects
				(font
					(size 1.27 1.27)
				)
				(justify mirror)
			)
		)
		(property "Value" ""
			(at 0 0 90)
			(layer "B.Fab")
			(effects
				(font
					(size 1.27 1.27)
				)
				(justify mirror)
			)
		)
		(duplicate_pad_numbers_are_jumpers no)
		(fp_line
			(start 0.7874 -0.4064)
			(end -0.7874 -0.4064)
			(stroke
				(width 0.1524)
				(type default)
			)
			(layer "B.SilkS")
		)
		(fp_line
			(start -0.7874 -0.4064)
			(end -0.7874 0.4064)
			(stroke
				(width 0.1524)
				(type default)
			)
			(layer "B.SilkS")
		)
		(fp_line
			(start 0.7874 0.4064)
			(end 0.7874 -0.4064)
			(stroke
				(width 0.1524)
				(type default)
			)
			(layer "B.SilkS")
		)
		(fp_line
			(start -0.7874 0.4064)
			(end 0.7874 0.4064)
			(stroke
				(width 0.1524)
				(type default)
			)
			(layer "B.SilkS")
		)
		(fp_line
			(start 0.67945 -0.305054)
			(end 0.12065 -0.305054)
			(stroke
				(width 0.1)
				(type default)
			)
			(layer "B.Fab")
		)
		(fp_line
			(start 0.12065 -0.305054)
			(end 0.12065 -0.2794)
			(stroke
				(width 0.1)
				(type default)
			)
			(layer "B.Fab")
		)
		(fp_line
			(start -0.12065 -0.3048)
			(end -0.67945 -0.3048)
			(stroke
				(width 0.1)
				(type default)
			)
			(layer "B.Fab")
		)
		(fp_line
			(start -0.67945 -0.3048)
			(end -0.67945 0.3048)
			(stroke
				(width 0.1)
				(type default)
			)
			(layer "B.Fab")
		)
		(fp_line
			(start 0.12065 -0.2794)
			(end -0.12065 -0.2794)
			(stroke
				(width 0.1)
				(type default)
			)
			(layer "B.Fab")
		)
		(fp_line
			(start -0.12065 -0.2794)
			(end -0.12065 -0.3048)
			(stroke
				(width 0.1)
				(type default)
			)
			(layer "B.Fab")
		)
		(fp_line
			(start 0.12065 0.2794)
			(end 0.12065 0.3048)
			(stroke
				(width 0.1)
				(type default)
			)
			(layer "B.Fab")
		)
		(fp_line
			(start -0.120396 0.2794)
			(end 0.12065 0.2794)
			(stroke
				(width 0.1)
				(type default)
			)
			(layer "B.Fab")
		)
		(fp_line
			(start 0.67945 0.3048)
			(end 0.67945 -0.305054)
			(stroke
				(width 0.1)
				(type default)
			)
			(layer "B.Fab")
		)
		(fp_line
			(start 0.12065 0.3048)
			(end 0.67945 0.3048)
			(stroke
				(width 0.1)
				(type default)
			)
			(layer "B.Fab")
		)
		(fp_line
			(start -0.120396 0.3048)
			(end -0.120396 0.2794)
			(stroke
				(width 0.1)
				(type default)
			)
			(layer "B.Fab")
		)
		(fp_line
			(start -0.67945 0.3048)
			(end -0.120396 0.3048)
			(stroke
				(width 0.1)
				(type default)
			)
			(layer "B.Fab")
		)
		(pad "1" smd circle
			(at 0.40005 0 270)
			(size 0 0)
			(layers "B.Cu" "B.Mask" "B.Paste")
			(net "VSENSE_P12V_INA230_5_INP")
		)
		(pad "2" smd circle
			(at -0.40005 0 270)
			(size 0 0)
			(layers "B.Cu" "B.Mask" "B.Paste")
			(net "VSENSE_P12V_INA230_5_INN")
		)
	)
)
